(kicad_pcb
	(version 20260206)
	(generator "pcbnew")
	(generator_version "10.0")
	(general
		(thickness 1.6)
		(legacy_teardrops no)
	)
	(paper "A4")
	(title_block
		(title "timecard-production-celestica-r4006 — R4006-B0001-02_R01.brd")
		(comment 1 "Time Appliance Project (Time Card) / footprints 552-560 of 1113")
	)
	(layers
		(0 "F.Cu" signal "TOP")
		(4 "In1.Cu" signal "L02_GND1")
		(6 "In2.Cu" signal "L03_SIG1")
		(8 "In3.Cu" signal "L04_GND2")
		(10 "In4.Cu" signal "L05_VCC1")
		(12 "In5.Cu" signal "L06_VCC2")
		(14 "In6.Cu" signal "L07_GND3")
		(16 "In7.Cu" signal "L08_SIG2")
		(18 "In8.Cu" signal "L09_GND4")
		(2 "B.Cu" signal "BOTTOM")
		(9 "F.Adhes" user "F.Adhesive")
		(11 "B.Adhes" user "B.Adhesive")
		(13 "F.Paste" user "Package Geometry/Pastemask Top")
		(15 "B.Paste" user "Package Geometry/Pastemask Bottom")
		(5 "F.SilkS" user "Ref Des/Silkscreen Top")
		(7 "B.SilkS" user "Ref Des/Silkscreen Bottom")
		(1 "F.Mask" user "Board Geometry/Soldermask Top")
		(3 "B.Mask" user "Board Geometry/Soldermask Bottom")
		(17 "Dwgs.User" user "User.Drawings")
		(19 "Cmts.User" user "User.Comments")
		(21 "Eco1.User" user "User.Eco1")
		(23 "Eco2.User" user "User.Eco2")
		(25 "Edge.Cuts" user "Board Geometry/Outline")
		(27 "Margin" user)
		(31 "F.CrtYd" user "Package Geometry/Place Bound Top")
		(29 "B.CrtYd" user "Package Geometry/Place Bound Bottom")
		(35 "F.Fab" user "Ref Des/Assembly Top")
		(33 "B.Fab" user "Ref Des/Assembly Bottom")
	)
	(footprint ""
		(layer "F.Cu")
		(at 144.653 -59.563 -90)
		(property "Reference" "C267"
			(at -3.048 2.11963 90)
			(unlocked yes)
			(layer "F.SilkS")
			(effects
				(font
					(size 0.7874 0.5842)
					(thickness 0.1524)
				)
			)
		)
		(property "Value" "VAL*"
			(at 0.193548 2.13614 270)
			(unlocked yes)
			(layer "F.Fab")
			(hide yes)
			(effects
				(font
					(size 0.7874 0.5842)
					(thickness 0.1524)
				)
			)
		)
		(property "Tolerance" "TOL*"
			(at 0.216154 3.1496 270)
			(unlocked yes)
			(layer "Cmts.User")
			(hide yes)
			(effects
				(font
					(size 0.7874 0.5842)
					(thickness 0.1524)
				)
			)
		)
		(property "Device Type" "CAPACITOR-G104-0B101-FK,100PF,A"
			(at 0.184404 1.180592 270)
			(unlocked yes)
			(layer "F.Fab")
			(hide yes)
			(effects
				(font
					(size 0.7874 0.5842)
					(thickness 0.1524)
				)
			)
		)
		(property "User Part Number" "PARTNUM*"
			(at 0.216154 4.185666 270)
			(unlocked yes)
			(layer "Cmts.User")
			(hide yes)
			(effects
				(font
					(size 0.7874 0.5842)
					(thickness 0.1524)
				)
			)
		)
		(duplicate_pad_numbers_are_jumpers no)
		(fp_line
			(start -0.671322 0.4445)
			(end -0.671322 -0.4445)
			(stroke
				(width 0.1)
				(type default)
			)
			(layer "F.SilkS")
		)
		(fp_line
			(start 0.671322 0.4445)
			(end -0.671322 0.4445)
			(stroke
				(width 0.1)
				(type default)
			)
			(layer "F.SilkS")
		)
		(fp_line
			(start -0.671322 -0.4445)
			(end 0.671322 -0.4445)
			(stroke
				(width 0.1)
				(type default)
			)
			(layer "F.SilkS")
		)
		(fp_line
			(start 0.671322 -0.4445)
			(end 0.671322 0.4445)
			(stroke
				(width 0.1)
				(type default)
			)
			(layer "F.SilkS")
		)
		(fp_rect
			(start 0.671322 0.4445)
			(end -0.671322 -0.4445)
			(stroke
				(width 0)
				(type default)
			)
			(fill no)
			(layer "F.CrtYd")
		)
		(fp_line
			(start -0.31496 0.1651)
			(end 0.31496 0.1651)
			(stroke
				(width 0.1)
				(type default)
			)
			(layer "F.Fab")
		)
		(fp_line
			(start 0.31496 0.1651)
			(end 0.31496 -0.1651)
			(stroke
				(width 0.1)
				(type default)
			)
			(layer "F.Fab")
		)
		(fp_line
			(start -0.31496 -0.1651)
			(end -0.31496 0.1651)
			(stroke
				(width 0.1)
				(type default)
			)
			(layer "F.Fab")
		)
		(fp_line
			(start 0.31496 -0.1651)
			(end -0.31496 -0.1651)
			(stroke
				(width 0.1)
				(type default)
			)
			(layer "F.Fab")
		)
		(pad "1" smd rect
			(at -0.264922 0 270)
			(size 0.3048 0.381)
			(layers "F.Cu" "F.Mask" "F.Paste")
			(net "UNNAMED_523_CAPACITOR_I28_1")
		)
		(pad "2" smd rect
			(at 0.264922 0 270)
			(size 0.3048 0.381)
			(layers "F.Cu" "F.Mask" "F.Paste")
			(net "XP1R0V_FB_R_TO_AGND")
		)
		(zone
			(layer "F.Cu")
			(hatch none 0.5)
			(connect_pads
				(clearance 0)
			)
			(min_thickness 0.25)
			(keepout
				(tracks allowed)
				(vias not_allowed)
				(pads allowed)
				(copperpour not_allowed)
				(footprints allowed)
			)
			(placement
				(enabled no)
				(sheetname "")
			)
			(fill
				(thermal_gap 0.5)
				(thermal_bridge_width 0.5)
				(island_removal_mode 0)
			)
			(polygon
				(pts
					(xy 144.4625 -59.450478) (xy 144.8435 -59.450478) (xy 144.8435 -59.675522) (xy 144.4625 -59.675522)
				)
			)
		)
	)
	(footprint ""
		(layer "F.Cu")
		(at 54.737 -125.349)
		(property "Reference" "SP56"
			(at 0 0 0)
			(layer "F.SilkS")
			(hide yes)
			(effects
				(font
					(size 1.27 1.27)
				)
			)
		)
		(property "Value" ""
			(at 0 0 0)
			(layer "F.Fab")
			(effects
				(font
					(size 1.27 1.27)
				)
			)
		)
		(duplicate_pad_numbers_are_jumpers no)
	)
	(footprint ""
		(layer "F.Cu")
		(at 53.594 -131.699)
		(property "Reference" "SP60"
			(at 0 0 0)
			(layer "F.SilkS")
			(hide yes)
			(effects
				(font
					(size 1.27 1.27)
				)
			)
		)
		(property "Value" ""
			(at 0 0 0)
			(layer "F.Fab")
			(effects
				(font
					(size 1.27 1.27)
				)
			)
		)
		(duplicate_pad_numbers_are_jumpers no)
	)
	(footprint ""
		(layer "F.Cu")
		(at 144.018 -20.1168 180)
		(property "Reference" "C230"
			(at -3.048 1.43383 0)
			(unlocked yes)
			(layer "F.SilkS")
			(effects
				(font
					(size 0.7874 0.5842)
					(thickness 0.1524)
				)
			)
		)
		(property "Value" "VAL*"
			(at 0.0762 2.067306 180)
			(unlocked yes)
			(layer "F.Fab")
			(hide yes)
			(effects
				(font
					(size 0.7874 0.5842)
					(thickness 0.1524)
				)
			)
		)
		(property "Tolerance" "TOL*"
			(at 0.0762 3.032506 180)
			(unlocked yes)
			(layer "Cmts.User")
			(hide yes)
			(effects
				(font
					(size 0.7874 0.5842)
					(thickness 0.1524)
				)
			)
		)
		(property "User Part Number" "PARTNUM*"
			(at 0.1016 4.023106 180)
			(unlocked yes)
			(layer "Cmts.User")
			(hide yes)
			(effects
				(font
					(size 0.7874 0.5842)
					(thickness 0.1524)
				)
			)
		)
		(property "Device Type" "CAPACITOR-G105-0B104-EK,0.1UF,A"
			(at 0.0508 1.127506 180)
			(unlocked yes)
			(layer "F.Fab")
			(hide yes)
			(effects
				(font
					(size 0.7874 0.5842)
					(thickness 0.1524)
				)
			)
		)
		(duplicate_pad_numbers_are_jumpers no)
		(fp_line
			(start 1.143 0.5588)
			(end 1.143 -0.5588)
			(stroke
				(width 0.1)
				(type default)
			)
			(layer "F.SilkS")
		)
		(fp_line
			(start 1.143 -0.5588)
			(end -1.143 -0.5588)
			(stroke
				(width 0.1)
				(type default)
			)
			(layer "F.SilkS")
		)
		(fp_line
			(start -1.143 0.5588)
			(end 1.143 0.5588)
			(stroke
				(width 0.1)
				(type default)
			)
			(layer "F.SilkS")
		)
		(fp_line
			(start -1.143 -0.5588)
			(end -1.143 0.5588)
			(stroke
				(width 0.1)
				(type default)
			)
			(layer "F.SilkS")
		)
		(fp_rect
			(start -1.143 0.5588)
			(end 1.143 -0.5588)
			(stroke
				(width 0)
				(type default)
			)
			(fill no)
			(layer "F.CrtYd")
		)
		(fp_line
			(start 0.508 0.3048)
			(end 0.508 -0.3048)
			(stroke
				(width 0.1)
				(type default)
			)
			(layer "F.Fab")
		)
		(fp_line
			(start 0.508 -0.3048)
			(end -0.508 -0.3048)
			(stroke
				(width 0.1)
				(type default)
			)
			(layer "F.Fab")
		)
		(fp_line
			(start -0.508 0.3048)
			(end 0.508 0.3048)
			(stroke
				(width 0.1)
				(type default)
			)
			(layer "F.Fab")
		)
		(fp_line
			(start -0.508 -0.3048)
			(end -0.508 0.3048)
			(stroke
				(width 0.1)
				(type default)
			)
			(layer "F.Fab")
		)
		(pad "1" smd rect
			(at -0.5334 0 180)
			(size 0.7112 0.6096)
			(layers "F.Cu" "F.Mask" "F.Paste")
			(net "UNNAMED_515_CAPACITOR_I130_1")
		)
		(pad "2" smd rect
			(at 0.5334 0 180)
			(size 0.7112 0.6096)
			(layers "F.Cu" "F.Mask" "F.Paste")
			(net "SG")
		)
		(zone
			(layer "F.Cu")
			(hatch none 0.5)
			(connect_pads
				(clearance 0)
			)
			(min_thickness 0.25)
			(keepout
				(tracks allowed)
				(vias not_allowed)
				(pads allowed)
				(copperpour not_allowed)
				(footprints allowed)
			)
			(placement
				(enabled no)
				(sheetname "")
			)
			(fill
				(thermal_gap 0.5)
				(thermal_bridge_width 0.5)
				(island_removal_mode 0)
			)
			(polygon
				(pts
					(xy 144.0942 -20.4216) (xy 143.9418 -20.4216) (xy 143.9418 -19.812) (xy 144.0942 -19.812)
				)
			)
		)
	)
	(footprint ""
		(layer "F.Cu")
		(at 18.669 -70.866 180)
		(property "Reference" "R73"
			(at -0.635 2.24663 0)
			(unlocked yes)
			(layer "F.SilkS")
			(effects
				(font
					(size 0.7874 0.5842)
					(thickness 0.1524)
				)
			)
		)
		(property "Value" "VAL*"
			(at 0.02032 2.13233 180)
			(unlocked yes)
			(layer "F.Fab")
			(hide yes)
			(effects
				(font
					(size 0.7874 0.5842)
					(thickness 0.1524)
				)
			)
		)
		(property "Tolerance" "TOL*"
			(at 0.044704 3.05435 180)
			(unlocked yes)
			(layer "Cmts.User")
			(hide yes)
			(effects
				(font
					(size 0.7874 0.5842)
					(thickness 0.1524)
				)
			)
		)
		(property "User Part Number" "PARTNUM*"
			(at 0.02032 4.024884 180)
			(unlocked yes)
			(layer "Cmts.User")
			(hide yes)
			(effects
				(font
					(size 0.7874 0.5842)
					(thickness 0.1524)
				)
			)
		)
		(property "Device Type" "RESISTOR-G155-133R0-01,33OHM,1%"
			(at 0.008382 1.210564 180)
			(unlocked yes)
			(layer "F.Fab")
			(hide yes)
			(effects
				(font
					(size 0.7874 0.5842)
					(thickness 0.1524)
				)
			)
		)
		(duplicate_pad_numbers_are_jumpers no)
		(fp_line
			(start 1.143 0.5588)
			(end 1.143 -0.5588)
			(stroke
				(width 0.1)
				(type default)
			)
			(layer "F.SilkS")
		)
		(fp_line
			(start 1.143 -0.5588)
			(end -1.143 -0.5588)
			(stroke
				(width 0.1)
				(type default)
			)
			(layer "F.SilkS")
		)
		(fp_line
			(start -1.143 0.5588)
			(end 1.143 0.5588)
			(stroke
				(width 0.1)
				(type default)
			)
			(layer "F.SilkS")
		)
		(fp_line
			(start -1.143 -0.5588)
			(end -1.143 0.5588)
			(stroke
				(width 0.1)
				(type default)
			)
			(layer "F.SilkS")
		)
		(fp_rect
			(start -1.143 0.5588)
			(end 1.143 -0.5588)
			(stroke
				(width 0)
				(type default)
			)
			(fill no)
			(layer "F.CrtYd")
		)
		(fp_line
			(start 0.508 0.3048)
			(end 0.508 -0.3048)
			(stroke
				(width 0.1)
				(type default)
			)
			(layer "F.Fab")
		)
		(fp_line
			(start 0.508 -0.3048)
			(end -0.508 -0.3048)
			(stroke
				(width 0.1)
				(type default)
			)
			(layer "F.Fab")
		)
		(fp_line
			(start -0.508 0.3048)
			(end 0.508 0.3048)
			(stroke
				(width 0.1)
				(type default)
			)
			(layer "F.Fab")
		)
		(fp_line
			(start -0.508 -0.3048)
			(end -0.508 0.3048)
			(stroke
				(width 0.1)
				(type default)
			)
			(layer "F.Fab")
		)
		(pad "1" smd rect
			(at -0.5334 0 180)
			(size 0.7112 0.6096)
			(layers "F.Cu" "F.Mask" "F.Paste")
			(net "BF_ICP10100_I2C_SCL")
		)
		(pad "2" smd rect
			(at 0.5334 0 180)
			(size 0.7112 0.6096)
			(layers "F.Cu" "F.Mask" "F.Paste")
			(net "R_ICP10100_I2C_SCL")
		)
		(zone
			(layer "F.Cu")
			(hatch none 0.5)
			(connect_pads
				(clearance 0)
			)
			(min_thickness 0.25)
			(keepout
				(tracks allowed)
				(vias not_allowed)
				(pads allowed)
				(copperpour not_allowed)
				(footprints allowed)
			)
			(placement
				(enabled no)
				(sheetname "")
			)
			(fill
				(thermal_gap 0.5)
				(thermal_bridge_width 0.5)
				(island_removal_mode 0)
			)
			(polygon
				(pts
					(xy 18.7452 -71.1708) (xy 18.5928 -71.1708) (xy 18.5928 -70.5612) (xy 18.7452 -70.5612)
				)
			)
		)
	)
	(footprint ""
		(layer "F.Cu")
		(at 46.228 -131.064)
		(property "Reference" "SP63"
			(at 0 0 0)
			(layer "F.SilkS")
			(hide yes)
			(effects
				(font
					(size 1.27 1.27)
				)
			)
		)
		(property "Value" ""
			(at 0 0 0)
			(layer "F.Fab")
			(effects
				(font
					(size 1.27 1.27)
				)
			)
		)
		(duplicate_pad_numbers_are_jumpers no)
	)
	(footprint ""
		(layer "F.Cu")
		(at 137.414 -46.101 90)
		(property "Reference" "C268"
			(at 3.302 -0.08763 90)
			(unlocked yes)
			(layer "F.SilkS")
			(effects
				(font
					(size 0.7874 0.5842)
					(thickness 0.1524)
				)
			)
		)
		(property "Value" "VAL*"
			(at 0.0762 2.067306 90)
			(unlocked yes)
			(layer "F.Fab")
			(hide yes)
			(effects
				(font
					(size 0.7874 0.5842)
					(thickness 0.1524)
				)
			)
		)
		(property "Device Type" "CAPACITOR-G105-0B104-CK,0.1UF,A"
			(at 0.0508 1.127506 90)
			(unlocked yes)
			(layer "F.Fab")
			(hide yes)
			(effects
				(font
					(size 0.7874 0.5842)
					(thickness 0.1524)
				)
			)
		)
		(property "User Part Number" "PARTNUM*"
			(at 0.1016 4.023106 90)
			(unlocked yes)
			(layer "Cmts.User")
			(hide yes)
			(effects
				(font
					(size 0.7874 0.5842)
					(thickness 0.1524)
				)
			)
		)
		(property "Tolerance" "TOL*"
			(at 0.0762 3.032506 90)
			(unlocked yes)
			(layer "Cmts.User")
			(hide yes)
			(effects
				(font
					(size 0.7874 0.5842)
					(thickness 0.1524)
				)
			)
		)
		(duplicate_pad_numbers_are_jumpers no)
		(fp_line
			(start 1.143 -0.5588)
			(end -1.143 -0.5588)
			(stroke
				(width 0.1)
				(type default)
			)
			(layer "F.SilkS")
		)
		(fp_line
			(start -1.143 -0.5588)
			(end -1.143 0.5588)
			(stroke
				(width 0.1)
				(type default)
			)
			(layer "F.SilkS")
		)
		(fp_line
			(start 1.143 0.5588)
			(end 1.143 -0.5588)
			(stroke
				(width 0.1)
				(type default)
			)
			(layer "F.SilkS")
		)
		(fp_line
			(start -1.143 0.5588)
			(end 1.143 0.5588)
			(stroke
				(width 0.1)
				(type default)
			)
			(layer "F.SilkS")
		)
		(fp_rect
			(start -1.143 -0.5588)
			(end 1.143 0.5588)
			(stroke
				(width 0)
				(type default)
			)
			(fill no)
			(layer "F.CrtYd")
		)
		(fp_line
			(start 0.508 -0.3048)
			(end -0.508 -0.3048)
			(stroke
				(width 0.1)
				(type default)
			)
			(layer "F.Fab")
		)
		(fp_line
			(start -0.508 -0.3048)
			(end -0.508 0.3048)
			(stroke
				(width 0.1)
				(type default)
			)
			(layer "F.Fab")
		)
		(fp_line
			(start 0.508 0.3048)
			(end 0.508 -0.3048)
			(stroke
				(width 0.1)
				(type default)
			)
			(layer "F.Fab")
		)
		(fp_line
			(start -0.508 0.3048)
			(end 0.508 0.3048)
			(stroke
				(width 0.1)
				(type default)
			)
			(layer "F.Fab")
		)
		(pad "1" smd rect
			(at -0.5334 0 90)
			(size 0.7112 0.6096)
			(layers "F.Cu" "F.Mask" "F.Paste")
			(net "XP1R0V_FPGA")
		)
		(pad "2" smd rect
			(at 0.5334 0 90)
			(size 0.7112 0.6096)
			(layers "F.Cu" "F.Mask" "F.Paste")
			(net "SG")
		)
		(zone
			(layer "F.Cu")
			(hatch none 0.5)
			(connect_pads
				(clearance 0)
			)
			(min_thickness 0.25)
			(keepout
				(tracks allowed)
				(vias not_allowed)
				(pads allowed)
				(copperpour not_allowed)
				(footprints allowed)
			)
			(placement
				(enabled no)
				(sheetname "")
			)
			(fill
				(thermal_gap 0.5)
				(thermal_bridge_width 0.5)
				(island_removal_mode 0)
			)
			(polygon
				(pts
					(xy 137.1092 -46.0248) (xy 137.7188 -46.0248) (xy 137.7188 -46.1772) (xy 137.1092 -46.1772)
				)
			)
		)
	)
	(footprint ""
		(layer "F.Cu")
		(at 67.555618 -23.734522)
		(property "Reference" "MAC_PIN7"
			(at -0.634238 2.580132 0)
			(unlocked yes)
			(layer "F.SilkS")
			(effects
				(font
					(size 0.7874 0.5842)
					(thickness 0.1524)
				)
			)
		)
		(property "Value" ""
			(at 0 0 0)
			(layer "F.Fab")
			(effects
				(font
					(size 1.27 1.27)
				)
			)
		)
		(property "Device Type" "NUT-A200-00029-FB"
			(at 0 2.632964 0)
			(unlocked yes)
			(layer "F.Fab")
			(hide yes)
			(effects
				(font
					(size 0.7874 0.5842)
					(thickness 0.1524)
				)
			)
		)
		(property "User Part Number" "PARTNUM*"
			(at 0 3.826764 0)
			(unlocked yes)
			(layer "Cmts.User")
			(hide yes)
			(effects
				(font
					(size 0.7874 0.5842)
					(thickness 0.1524)
				)
			)
		)
		(duplicate_pad_numbers_are_jumpers no)
		(fp_circle
			(center 0 0)
			(end 1.524 0)
			(stroke
				(width 0.1)
				(type default)
			)
			(fill no)
			(layer "F.SilkS")
		)
		(fp_poly
			(pts
				(arc
					(start -1.260856 -0.1524)
					(mid -0.898049 -0.898049)
					(end -0.1524 -1.260856)
				)
				(arc
					(start -0.1524 -0.991616)
					(mid -0.709411 -0.709411)
					(end -0.991616 -0.1524)
				)
			)
			(stroke
				(width 0)
				(type default)
			)
			(fill yes)
			(layer "F.Paste")
		)
		(fp_poly
			(pts
				(arc
					(start -0.1524 1.260856)
					(mid -0.898049 0.898049)
					(end -1.260856 0.1524)
				)
				(arc
					(start -0.991616 0.1524)
					(mid -0.709411 0.709411)
					(end -0.1524 0.991616)
				)
			)
			(stroke
				(width 0)
				(type default)
			)
			(fill yes)
			(layer "F.Paste")
		)
		(fp_poly
			(pts
				(arc
					(start 0.1524 -1.260856)
					(mid 0.898049 -0.898049)
					(end 1.260856 -0.1524)
				)
				(arc
					(start 0.991616 -0.1524)
					(mid 0.709411 -0.709411)
					(end 0.1524 -0.991616)
				)
			)
			(stroke
				(width 0)
				(type default)
			)
			(fill yes)
			(layer "F.Paste")
		)
		(fp_poly
			(pts
				(arc
					(start 1.260856 0.1524)
					(mid 0.898049 0.898049)
					(end 0.1524 1.260856)
				)
				(arc
					(start 0.1524 0.991616)
					(mid 0.709411 0.709411)
					(end 0.991616 0.1524)
				)
			)
			(stroke
				(width 0)
				(type default)
			)
			(fill yes)
			(layer "F.Paste")
		)
		(fp_poly
			(pts
				(arc
					(start 6.35 0)
					(mid -6.35 0)
					(end 6.35 0)
				)
			)
			(stroke
				(width 0)
				(type default)
			)
			(fill no)
			(layer "B.CrtYd")
		)
		(fp_poly
			(pts
				(arc
					(start 1.778 0)
					(mid -1.778 0)
					(end 1.778 0)
				)
			)
			(stroke
				(width 0)
				(type default)
			)
			(fill no)
			(layer "F.CrtYd")
		)
		(fp_circle
			(center 0 0)
			(end 1.1684 0)
			(stroke
				(width 0.1)
				(type default)
			)
			(fill no)
			(layer "F.Fab")
		)
		(pad "1" thru_hole circle
			(at 0 0)
			(size 2.54 2.54)
			(drill 2.0066)
			(layers "*.Cu" "*.Mask")
			(remove_unused_layers no)
			(net "R_MAC_UART_TX_FPGA_RX")
			(thermal_gap 0.0254)
			(padstack
				(mode front_inner_back)
				(layer "Inner"
					(shape circle)
					(size 2.54 2.54)
					(clearance 0.0254)
				)
				(layer "B.Cu"
					(shape circle)
					(size 2.54 2.54)
				)
			)
		)
	)
	(footprint ""
		(layer "F.Cu")
		(at 118.618 -90.297)
		(property "Reference" "TP15"
			(at -1.9812 1.30937 0)
			(unlocked yes)
			(layer "F.SilkS")
			(effects
				(font
					(size 0.7874 0.5842)
					(thickness 0.1524)
				)
				(justify left)
			)
		)
		(property "Value" ""
			(at 0 0 0)
			(layer "F.Fab")
			(effects
				(font
					(size 1.27 1.27)
				)
			)
		)
		(property "Device Type" "TP_PIONT-TP010CT020B030_PTH-TPA"
			(at -1.341882 0.996696 0)
			(unlocked yes)
			(layer "F.Fab")
			(hide yes)
			(effects
				(font
					(size 0.7874 0.5842)
					(thickness 0.000001)
				)
				(justify left)
			)
		)
		(duplicate_pad_numbers_are_jumpers no)
		(fp_poly
			(pts
				(arc
					(start 0.889 0)
					(mid -0.889 0)
					(end 0.889 0)
				)
			)
			(stroke
				(width 0)
				(type default)
			)
			(fill no)
			(layer "B.CrtYd")
		)
		(fp_poly
			(pts
				(arc
					(start 0.889 0)
					(mid -0.889 0)
					(end 0.889 0)
				)
			)
			(stroke
				(width 0)
				(type default)
			)
			(fill no)
			(layer "F.CrtYd")
		)
		(pad "1" thru_hole circle
			(at 0 0)
			(size 0.508 0.508)
			(drill 0.254)
			(layers "*.Cu" "*.Mask")
			(remove_unused_layers no)
			(net "GPS_RST_N")
			(clearance 0.1016)
			(padstack
				(mode front_inner_back)
				(layer "Inner"
					(shape circle)
					(size 0.508 0.508)
					(clearance 0.1016)
				)
				(layer "B.Cu"
					(shape circle)
					(size 0.762 0.762)
					(clearance -0.0254)
				)
			)
		)
	)
)
